(kicad_pcb
	(version 20260206)
	(generator "pcbnew")
	(generator_version "10.0")
	(general
		(thickness 1.6)
		(legacy_teardrops no)
	)
	(paper "A4")
	(title_block
		(title "baseboard — 13948-1b.1110WZS1818.brd")
		(comment 1 "Honey Badger (Wiwynn) / footprints 1895-1904 of 2523")
	)
	(layers
		(0 "F.Cu" signal "TOP")
		(4 "In1.Cu" signal "L2GND")
		(6 "In2.Cu" signal "L3")
		(8 "In3.Cu" signal "L4VCC")
		(10 "In4.Cu" signal "L5VCC")
		(12 "In5.Cu" signal "L6")
		(14 "In6.Cu" signal "L7GND")
		(2 "B.Cu" signal "BOTTOM")
		(9 "F.Adhes" user "F.Adhesive")
		(11 "B.Adhes" user "B.Adhesive")
		(13 "F.Paste" user "Package Geometry/Pastemask Top")
		(15 "B.Paste" user "Package Geometry/Pastemask Bottom")
		(5 "F.SilkS" user "Ref Des/Silkscreen Top")
		(7 "B.SilkS" user "Ref Des/Silkscreen Bottom")
		(1 "F.Mask" user "Board Geometry/Soldermask Top")
		(3 "B.Mask" user "Board Geometry/Soldermask Bottom")
		(17 "Dwgs.User" user "User.Drawings")
		(19 "Cmts.User" user "User.Comments")
		(21 "Eco1.User" user "User.Eco1")
		(23 "Eco2.User" user "User.Eco2")
		(25 "Edge.Cuts" user "Board Geometry/Outline")
		(27 "Margin" user)
		(31 "F.CrtYd" user "Package Geometry/Place Bound Top")
		(29 "B.CrtYd" user "Package Geometry/Place Bound Bottom")
		(35 "F.Fab" user "Ref Des/Assembly Top")
		(33 "B.Fab" user "Ref Des/Assembly Bottom")
	)
	(footprint ""
		(layer "B.Cu")
		(at 124.403612 -216.535 -90)
		(property "Reference" "SR1271"
			(at 0 0 90)
			(layer "B.SilkS")
			(hide yes)
			(effects
				(font
					(size 1.27 1.27)
				)
				(justify mirror)
			)
		)
		(property "Value" "0R2J-2-GP"
			(at -0.064008 -3.993896 270)
			(unlocked yes)
			(layer "B.Fab")
			(hide yes)
			(effects
				(font
					(size 1.016 1.016)
					(thickness 0.1524)
				)
				(justify mirror)
			)
		)
		(property "Device Type" "R402H16"
			(at -0.064008 -5.517896 270)
			(unlocked yes)
			(layer "B.Fab")
			(hide yes)
			(effects
				(font
					(size 1.016 1.016)
					(thickness 0.1524)
				)
				(justify mirror)
			)
		)
		(duplicate_pad_numbers_are_jumpers no)
		(fp_line
			(start -0.508 -0.9398)
			(end 0.508 -0.9398)
			(stroke
				(width 0.1524)
				(type default)
			)
			(layer "B.SilkS")
		)
		(fp_line
			(start 0.508 -0.9398)
			(end 0.508 0.9398)
			(stroke
				(width 0.1524)
				(type default)
			)
			(layer "B.SilkS")
		)
		(fp_rect
			(start 0.508 0.9398)
			(end -0.508 -0.9398)
			(stroke
				(width 0)
				(type default)
			)
			(fill no)
			(layer "B.CrtYd")
		)
		(fp_rect
			(start 0.508 0.9398)
			(end -0.508 -0.9398)
			(stroke
				(width 0)
				(type default)
			)
			(fill no)
			(layer "B.Fab")
		)
		(pad "1" smd custom
			(at 0 -0.4445 90)
			(size 0.1397 0.1397)
			(layers "B.Cu" "B.Mask" "B.Paste")
			(net "EXP_SCL_L_0")
			(options
				(clearance outline)
				(anchor circle)
			)
			(primitives
				(gr_poly
					(pts
						(arc
							(start -0.1778 0.2794)
							(mid -0.249642 0.249642)
							(end -0.2794 0.1778)
						)
						(arc
							(start -0.2794 -0.1778)
							(mid -0.249642 -0.249642)
							(end -0.1778 -0.2794)
						)
						(arc
							(start 0.1778 -0.2794)
							(mid 0.249642 -0.249642)
							(end 0.2794 -0.1778)
						)
						(arc
							(start 0.2794 0.1778)
							(mid 0.249642 0.249642)
							(end 0.1778 0.2794)
						)
					)
					(width 0)
					(fill yes)
				)
			)
		)
		(pad "2" smd custom
			(at 0 0.4445 90)
			(size 0.1397 0.1397)
			(layers "B.Cu" "B.Mask" "B.Paste")
			(net "REDV_I2C_SCL")
			(options
				(clearance outline)
				(anchor circle)
			)
			(primitives
				(gr_poly
					(pts
						(arc
							(start -0.1778 0.2794)
							(mid -0.249642 0.249642)
							(end -0.2794 0.1778)
						)
						(arc
							(start -0.2794 -0.1778)
							(mid -0.249642 -0.249642)
							(end -0.1778 -0.2794)
						)
						(arc
							(start 0.1778 -0.2794)
							(mid 0.249642 -0.249642)
							(end 0.2794 -0.1778)
						)
						(arc
							(start 0.2794 0.1778)
							(mid 0.249642 0.249642)
							(end 0.1778 0.2794)
						)
					)
					(width 0)
					(fill yes)
				)
			)
		)
	)
	(footprint ""
		(layer "B.Cu")
		(at 114.154966 -36.957)
		(property "Reference" "STP6"
			(at 0 0 0)
			(layer "B.SilkS")
			(hide yes)
			(effects
				(font
					(size 1.27 1.27)
				)
				(justify mirror)
			)
		)
		(property "Value" "TPAD28"
			(at -0.0127 -1.8034 0)
			(unlocked yes)
			(layer "B.Fab")
			(hide yes)
			(effects
				(font
					(size 1.016 1.016)
					(thickness 0.1524)
				)
				(justify mirror)
			)
		)
		(property "Device Type" "TPAD28"
			(at -0.0127 -3.3274 0)
			(unlocked yes)
			(layer "B.Fab")
			(hide yes)
			(effects
				(font
					(size 1.016 1.016)
					(thickness 0.1524)
				)
				(justify mirror)
			)
		)
		(duplicate_pad_numbers_are_jumpers no)
		(fp_poly
			(pts
				(arc
					(start 0.3556 0)
					(mid -0.3556 0)
					(end 0.3556 0)
				)
			)
			(stroke
				(width 0)
				(type default)
			)
			(fill no)
			(layer "B.CrtYd")
		)
		(fp_poly
			(pts
				(arc
					(start 0.6096 0)
					(mid -0.6096 0)
					(end 0.6096 0)
				)
			)
			(stroke
				(width 0)
				(type default)
			)
			(fill no)
			(layer "B.Fab")
		)
		(pad "1" smd circle
			(at 0 0 180)
			(size 0.7112 0.7112)
			(layers "B.Cu" "B.Mask" "B.Paste")
			(net "IOC_GPIO_27")
		)
	)
	(footprint ""
		(layer "B.Cu")
		(at 111.38916 -33.655)
		(property "Reference" "STP50"
			(at 0 0 0)
			(layer "B.SilkS")
			(hide yes)
			(effects
				(font
					(size 1.27 1.27)
				)
				(justify mirror)
			)
		)
		(property "Value" "TPAD28"
			(at -0.0127 -1.8034 0)
			(unlocked yes)
			(layer "B.Fab")
			(hide yes)
			(effects
				(font
					(size 1.016 1.016)
					(thickness 0.1524)
				)
				(justify mirror)
			)
		)
		(property "Device Type" "TPAD28"
			(at -0.0127 -3.3274 0)
			(unlocked yes)
			(layer "B.Fab")
			(hide yes)
			(effects
				(font
					(size 1.016 1.016)
					(thickness 0.1524)
				)
				(justify mirror)
			)
		)
		(duplicate_pad_numbers_are_jumpers no)
		(fp_poly
			(pts
				(arc
					(start 0.3556 0)
					(mid -0.3556 0)
					(end 0.3556 0)
				)
			)
			(stroke
				(width 0)
				(type default)
			)
			(fill no)
			(layer "B.CrtYd")
		)
		(fp_poly
			(pts
				(arc
					(start 0.6096 0)
					(mid -0.6096 0)
					(end 0.6096 0)
				)
			)
			(stroke
				(width 0)
				(type default)
			)
			(fill no)
			(layer "B.Fab")
		)
		(pad "1" smd circle
			(at 0 0 180)
			(size 0.7112 0.7112)
			(layers "B.Cu" "B.Mask" "B.Paste")
			(net "SPARE0")
		)
	)
	(footprint ""
		(layer "B.Cu")
		(at 114.84737 -90.8812 90)
		(property "Reference" "SC1248"
			(at 0 0 90)
			(layer "B.SilkS")
			(hide yes)
			(effects
				(font
					(size 1.27 1.27)
				)
				(justify mirror)
			)
		)
		(property "Value" "SCD1U6D3V1KX-GP"
			(at 2.8321 -1.7399 90)
			(unlocked yes)
			(layer "B.Fab")
			(hide yes)
			(effects
				(font
					(size 1.016 1.016)
					(thickness 0.1524)
				)
				(justify mirror)
			)
		)
		(property "Device Type" "C0201H13"
			(at 2.8321 -3.2639 90)
			(unlocked yes)
			(layer "B.Fab")
			(hide yes)
			(effects
				(font
					(size 1.016 1.016)
					(thickness 0.1524)
				)
				(justify mirror)
			)
		)
		(duplicate_pad_numbers_are_jumpers no)
		(fp_rect
			(start 0.2794 0.6477)
			(end -0.2794 -0.6477)
			(stroke
				(width 0)
				(type default)
			)
			(fill no)
			(layer "B.CrtYd")
		)
		(fp_rect
			(start 0.2794 0.6477)
			(end -0.2794 -0.6477)
			(stroke
				(width 0)
				(type default)
			)
			(fill no)
			(layer "B.Fab")
		)
		(pad "1" smd custom
			(at 0 -0.2794 270)
			(size 0.0762 0.0762)
			(layers "B.Cu" "B.Mask" "B.Paste")
			(net "P0V9_E")
			(options
				(clearance outline)
				(anchor circle)
			)
			(primitives
				(gr_poly
					(pts
						(arc
							(start 0.1524 0.127)
							(mid 0.137521 0.162921)
							(end 0.1016 0.1778)
						)
						(arc
							(start -0.1016 0.1778)
							(mid -0.137521 0.162921)
							(end -0.1524 0.127)
						)
						(arc
							(start -0.1524 -0.127)
							(mid -0.137521 -0.162921)
							(end -0.1016 -0.1778)
						)
						(arc
							(start 0.1016 -0.1778)
							(mid 0.137521 -0.162921)
							(end 0.1524 -0.127)
						)
					)
					(width 0)
					(fill yes)
				)
			)
		)
		(pad "2" smd custom
			(at 0 0.2794 270)
			(size 0.0762 0.0762)
			(layers "B.Cu" "B.Mask" "B.Paste")
			(net "GND")
			(options
				(clearance outline)
				(anchor circle)
			)
			(primitives
				(gr_poly
					(pts
						(arc
							(start 0.1524 0.127)
							(mid 0.137521 0.162921)
							(end 0.1016 0.1778)
						)
						(arc
							(start -0.1016 0.1778)
							(mid -0.137521 0.162921)
							(end -0.1524 0.127)
						)
						(arc
							(start -0.1524 -0.127)
							(mid -0.137521 -0.162921)
							(end -0.1016 -0.1778)
						)
						(arc
							(start 0.1016 -0.1778)
							(mid 0.137521 -0.162921)
							(end 0.1524 -0.127)
						)
					)
					(width 0)
					(fill yes)
				)
			)
		)
	)
	(footprint ""
		(layer "B.Cu")
		(at 342.921336 -71.797672)
		(property "Reference" "R265"
			(at 0 0 0)
			(layer "B.SilkS")
			(hide yes)
			(effects
				(font
					(size 1.27 1.27)
				)
				(justify mirror)
			)
		)
		(property "Value" "0R0402-PAD-1-GP"
			(at -0.064008 -3.993896 0)
			(unlocked yes)
			(layer "B.Fab")
			(hide yes)
			(effects
				(font
					(size 1.016 1.016)
					(thickness 0.1524)
				)
				(justify mirror)
			)
		)
		(property "Device Type" "0R0402-PAD"
			(at -0.064008 -5.517896 0)
			(unlocked yes)
			(layer "B.Fab")
			(hide yes)
			(effects
				(font
					(size 1.016 1.016)
					(thickness 0.1524)
				)
				(justify mirror)
			)
		)
		(duplicate_pad_numbers_are_jumpers no)
		(fp_line
			(start -0.508 -0.9398)
			(end 0.508 -0.9398)
			(stroke
				(width 0.1524)
				(type default)
			)
			(layer "B.SilkS")
		)
		(fp_line
			(start 0.508 -0.9398)
			(end 0.508 0.9398)
			(stroke
				(width 0.1524)
				(type default)
			)
			(layer "B.SilkS")
		)
		(fp_rect
			(start 0.508 0.9398)
			(end -0.508 -0.9398)
			(stroke
				(width 0)
				(type default)
			)
			(fill no)
			(layer "B.CrtYd")
		)
		(fp_rect
			(start 0.508 0.9398)
			(end -0.508 -0.9398)
			(stroke
				(width 0)
				(type default)
			)
			(fill no)
			(layer "B.Fab")
		)
		(pad "1" smd custom
			(at 0 -0.4445 180)
			(size 0.1397 0.1397)
			(layers "B.Cu" "B.Mask" "B.Paste")
			(net "P3V3_STBY")
			(options
				(clearance outline)
				(anchor circle)
			)
			(primitives
				(gr_poly
					(pts
						(xy -0.2794 -0.3683)
						(arc
							(start -0.2794 0.2667)
							(mid -0.249642 0.338542)
							(end -0.1778 0.3683)
						)
						(arc
							(start 0.1778 0.3683)
							(mid 0.249642 0.338542)
							(end 0.2794 0.2667)
						)
						(xy 0.2794 -0.3683)
					)
					(width 0)
					(fill yes)
				)
			)
		)
		(pad "2" smd custom
			(at 0 0.4445 180)
			(size 0.1397 0.1397)
			(layers "B.Cu" "B.Mask" "B.Paste")
			(net "FLA_WPN")
			(options
				(clearance outline)
				(anchor circle)
			)
			(primitives
				(gr_poly
					(pts
						(arc
							(start -0.1778 -0.3683)
							(mid -0.249642 -0.338542)
							(end -0.2794 -0.2667)
						)
						(xy -0.2794 0.3683) (xy 0.2794 0.3683)
						(arc
							(start 0.2794 -0.2667)
							(mid 0.249642 -0.338542)
							(end 0.1778 -0.3683)
						)
					)
					(width 0)
					(fill yes)
				)
			)
		)
	)
	(footprint ""
		(layer "B.Cu")
		(at 108.72216 -31.369)
		(property "Reference" "STP130"
			(at 0 0 0)
			(layer "B.SilkS")
			(hide yes)
			(effects
				(font
					(size 1.27 1.27)
				)
				(justify mirror)
			)
		)
		(property "Value" "TPAD28"
			(at -0.0127 -1.8034 0)
			(unlocked yes)
			(layer "B.Fab")
			(hide yes)
			(effects
				(font
					(size 1.016 1.016)
					(thickness 0.1524)
				)
				(justify mirror)
			)
		)
		(property "Device Type" "TPAD28"
			(at -0.0127 -3.3274 0)
			(unlocked yes)
			(layer "B.Fab")
			(hide yes)
			(effects
				(font
					(size 1.016 1.016)
					(thickness 0.1524)
				)
				(justify mirror)
			)
		)
		(duplicate_pad_numbers_are_jumpers no)
		(fp_poly
			(pts
				(arc
					(start 0.3556 0)
					(mid -0.3556 0)
					(end 0.3556 0)
				)
			)
			(stroke
				(width 0)
				(type default)
			)
			(fill no)
			(layer "B.CrtYd")
		)
		(fp_poly
			(pts
				(arc
					(start 0.6096 0)
					(mid -0.6096 0)
					(end 0.6096 0)
				)
			)
			(stroke
				(width 0)
				(type default)
			)
			(fill no)
			(layer "B.Fab")
		)
		(pad "1" smd circle
			(at 0 0 180)
			(size 0.7112 0.7112)
			(layers "B.Cu" "B.Mask" "B.Paste")
			(net "IOC_GPIO_13")
		)
	)
	(footprint ""
		(layer "B.Cu")
		(at 349.749872 -37.399722)
		(property "Reference" ""
			(at 0 0 0)
			(layer "B.SilkS")
			(hide yes)
			(effects
				(font
					(size 1.27 1.27)
				)
				(justify mirror)
			)
		)
		(property "Value" "*"
			(at 5.5753 -0.4572 0)
			(unlocked yes)
			(layer "B.Fab")
			(hide yes)
			(effects
				(font
					(size 1.016 1.016)
					(thickness 0.1524)
				)
				(justify mirror)
			)
		)
		(duplicate_pad_numbers_are_jumpers no)
		(fp_poly
			(pts
				(arc
					(start 4.3053 0)
					(mid -4.3053 0)
					(end 4.3053 0)
				)
			)
			(stroke
				(width 0)
				(type default)
			)
			(fill no)
			(layer "B.CrtYd")
		)
		(fp_poly
			(pts
				(arc
					(start 4.3053 0)
					(mid -4.3053 0)
					(end 4.3053 0)
				)
			)
			(stroke
				(width 0)
				(type default)
			)
			(fill no)
			(layer "B.Fab")
		)
		(pad "1" smd custom
			(at 2.95275 0 180)
			(size 2.000013 2.000013)
			(layers "B.Cu" "B.Mask" "B.Paste")
			(net "Net_55")
			(options
				(clearance outline)
				(anchor circle)
			)
			(primitives
				(gr_poly
					(pts
						(arc
							(start 4.0005 -0.00254)
							(mid -4.000501 0)
							(end 4.0005 0.00254)
						)
						(arc
							(start 1.905 0.00254)
							(mid -1.905002 0)
							(end 1.905 -0.00254)
						)
					)
					(width 0)
					(fill yes)
				)
			)
		)
	)
	(footprint ""
		(layer "B.Cu")
		(at 96.730566 -48.1584)
		(property "Reference" "SR680"
			(at 0 0 0)
			(layer "B.SilkS")
			(hide yes)
			(effects
				(font
					(size 1.27 1.27)
				)
				(justify mirror)
			)
		)
		(property "Value" "4K7R2F-GP"
			(at -0.064008 -3.993896 0)
			(unlocked yes)
			(layer "B.Fab")
			(hide yes)
			(effects
				(font
					(size 1.016 1.016)
					(thickness 0.1524)
				)
				(justify mirror)
			)
		)
		(property "Device Type" "R402H16"
			(at -0.064008 -5.517896 0)
			(unlocked yes)
			(layer "B.Fab")
			(hide yes)
			(effects
				(font
					(size 1.016 1.016)
					(thickness 0.1524)
				)
				(justify mirror)
			)
		)
		(duplicate_pad_numbers_are_jumpers no)
		(fp_line
			(start -0.508 -0.9398)
			(end 0.508 -0.9398)
			(stroke
				(width 0.1524)
				(type default)
			)
			(layer "B.SilkS")
		)
		(fp_line
			(start 0.508 -0.9398)
			(end 0.508 0.9398)
			(stroke
				(width 0.1524)
				(type default)
			)
			(layer "B.SilkS")
		)
		(fp_rect
			(start 0.508 0.9398)
			(end -0.508 -0.9398)
			(stroke
				(width 0)
				(type default)
			)
			(fill no)
			(layer "B.CrtYd")
		)
		(fp_rect
			(start 0.508 0.9398)
			(end -0.508 -0.9398)
			(stroke
				(width 0)
				(type default)
			)
			(fill no)
			(layer "B.Fab")
		)
		(pad "1" smd custom
			(at 0 -0.4445 180)
			(size 0.1397 0.1397)
			(layers "B.Cu" "B.Mask" "B.Paste")
			(net "P1V8_C")
			(options
				(clearance outline)
				(anchor circle)
			)
			(primitives
				(gr_poly
					(pts
						(arc
							(start -0.1778 0.2794)
							(mid -0.249642 0.249642)
							(end -0.2794 0.1778)
						)
						(arc
							(start -0.2794 -0.1778)
							(mid -0.249642 -0.249642)
							(end -0.1778 -0.2794)
						)
						(arc
							(start 0.1778 -0.2794)
							(mid 0.249642 -0.249642)
							(end 0.2794 -0.1778)
						)
						(arc
							(start 0.2794 0.1778)
							(mid 0.249642 0.249642)
							(end 0.1778 0.2794)
						)
					)
					(width 0)
					(fill yes)
				)
			)
		)
		(pad "2" smd custom
			(at 0 0.4445 180)
			(size 0.1397 0.1397)
			(layers "B.Cu" "B.Mask" "B.Paste")
			(net "ICE_SEL")
			(options
				(clearance outline)
				(anchor circle)
			)
			(primitives
				(gr_poly
					(pts
						(arc
							(start -0.1778 0.2794)
							(mid -0.249642 0.249642)
							(end -0.2794 0.1778)
						)
						(arc
							(start -0.2794 -0.1778)
							(mid -0.249642 -0.249642)
							(end -0.1778 -0.2794)
						)
						(arc
							(start 0.1778 -0.2794)
							(mid 0.249642 -0.249642)
							(end 0.2794 -0.1778)
						)
						(arc
							(start 0.2794 0.1778)
							(mid 0.249642 0.249642)
							(end 0.1778 0.2794)
						)
					)
					(width 0)
					(fill yes)
				)
			)
		)
	)
	(footprint ""
		(layer "B.Cu")
		(at 124.799852 -20.299934)
		(property "Reference" ""
			(at 0 0 0)
			(layer "B.SilkS")
			(hide yes)
			(effects
				(font
					(size 1.27 1.27)
				)
				(justify mirror)
			)
		)
		(property "Value" "*"
			(at 5.5753 -0.4572 0)
			(unlocked yes)
			(layer "B.Fab")
			(hide yes)
			(effects
				(font
					(size 1.016 1.016)
					(thickness 0.1524)
				)
				(justify mirror)
			)
		)
		(duplicate_pad_numbers_are_jumpers no)
		(fp_poly
			(pts
				(arc
					(start 4.3053 0)
					(mid -4.3053 0)
					(end 4.3053 0)
				)
			)
			(stroke
				(width 0)
				(type default)
			)
			(fill no)
			(layer "B.CrtYd")
		)
		(fp_poly
			(pts
				(arc
					(start 4.3053 0)
					(mid -4.3053 0)
					(end 4.3053 0)
				)
			)
			(stroke
				(width 0)
				(type default)
			)
			(fill no)
			(layer "B.Fab")
		)
		(pad "1" smd custom
			(at 2.95275 0 180)
			(size 2.000013 2.000013)
			(layers "B.Cu" "B.Mask" "B.Paste")
			(net "Net_49")
			(options
				(clearance outline)
				(anchor circle)
			)
			(primitives
				(gr_poly
					(pts
						(arc
							(start 4.0005 -0.00254)
							(mid -4.000501 0)
							(end 4.0005 0.00254)
						)
						(arc
							(start 1.905 0.00254)
							(mid -1.905002 0)
							(end 1.905 -0.00254)
						)
					)
					(width 0)
					(fill yes)
				)
			)
		)
	)
	(footprint ""
		(layer "B.Cu")
		(at 127.11557 -88.265 90)
		(property "Reference" "SC1175"
			(at 0 0 90)
			(layer "B.SilkS")
			(hide yes)
			(effects
				(font
					(size 1.27 1.27)
				)
				(justify mirror)
			)
		)
		(property "Value" "SCD1U16V2KX-3GP"
			(at -1.1811 -2.7051 90)
			(unlocked yes)
			(layer "B.Fab")
			(hide yes)
			(effects
				(font
					(size 1.016 1.016)
					(thickness 0.1524)
				)
				(justify mirror)
			)
		)
		(property "Device Type" "C402H22"
			(at -1.1811 -4.2291 90)
			(unlocked yes)
			(layer "B.Fab")
			(hide yes)
			(effects
				(font
					(size 1.016 1.016)
					(thickness 0.1524)
				)
				(justify mirror)
			)
		)
		(duplicate_pad_numbers_are_jumpers no)
		(fp_rect
			(start 0.4318 0.9525)
			(end -0.4318 -0.9525)
			(stroke
				(width 0)
				(type default)
			)
			(fill no)
			(layer "B.CrtYd")
		)
		(fp_rect
			(start 0.4318 0.9525)
			(end -0.4318 -0.9525)
			(stroke
				(width 0)
				(type default)
			)
			(fill no)
			(layer "B.Fab")
		)
		(pad "1" smd custom
			(at 0 -0.4445 270)
			(size 0.1524 0.1524)
			(layers "B.Cu" "B.Mask" "B.Paste")
			(net "GB_VDDA")
			(options
				(clearance outline)
				(anchor circle)
			)
			(primitives
				(gr_poly
					(pts
						(arc
							(start 0.3048 0.2032)
							(mid 0.275042 0.275042)
							(end 0.2032 0.3048)
						)
						(arc
							(start -0.2032 0.3048)
							(mid -0.275042 0.275042)
							(end -0.3048 0.2032)
						)
						(arc
							(start -0.3048 -0.2032)
							(mid -0.275042 -0.275042)
							(end -0.2032 -0.3048)
						)
						(arc
							(start 0.2032 -0.3048)
							(mid 0.275042 -0.275042)
							(end 0.3048 -0.2032)
						)
					)
					(width 0)
					(fill yes)
				)
			)
		)
		(pad "2" smd custom
			(at 0 0.4445 270)
			(size 0.1524 0.1524)
			(layers "B.Cu" "B.Mask" "B.Paste")
			(net "GND")
			(options
				(clearance outline)
				(anchor circle)
			)
			(primitives
				(gr_poly
					(pts
						(arc
							(start 0.3048 0.2032)
							(mid 0.275042 0.275042)
							(end 0.2032 0.3048)
						)
						(arc
							(start -0.2032 0.3048)
							(mid -0.275042 0.275042)
							(end -0.3048 0.2032)
						)
						(arc
							(start -0.3048 -0.2032)
							(mid -0.275042 -0.275042)
							(end -0.2032 -0.3048)
						)
						(arc
							(start 0.2032 -0.3048)
							(mid 0.275042 -0.275042)
							(end 0.3048 -0.2032)
						)
					)
					(width 0)
					(fill yes)
				)
			)
		)
	)
)
